FILE_TYPE = CONNECTIVITY;
{Allegro Design Entry HDL 17.2-2016 S081 (4005846) 1/11/2022}
"PAGE_NUMBER" = 55;
0"NC";
1"GND\g"$PHYS_NET_NAME"GND"VOLTAGE"0";
2"GND\g";
3"GND\g";
4"GND\g";
5"PVDD18_S5_P1\g";
6"GND\g";
7"GND\g";
8"XTAL_CPU1_R_X32K_X1";
9"XTAL_CPU1_R_X32K_X2";
10"PVDD18_S5_P1\g";
11"CPU1_FORCE_SELFREFRESH";
12"RST_CPU1_RESETL_N";
13"CPU1_SPD_HOST_CTRL_N";
14"PWRGD_CPU1_PWROK";
15"CPU1_FPGA_SPARE3";
16"CPU1_NV_SAVE_N";
17"CPU1_SMERR_N";
18"CPU1_FPGA_SPARE2";
19"CPU1_FPGA_SPARE1";
20"RST_CPU1_SYS_N";
21"CPU1_NMI_SYNC_FLOOD_N";
22"CPU1_FPGA_SPARE0";
23"PVDD11_S3_P1\g";
24"PVDD18_S5_P1\g";
25"I3C_1_SPD_DDRGL_CPU1_R_SDA";
26"I3C_0_SPD_DDRAF_CPU1_R_SCL";
27"I3C_0_SPD_DDRAF_CPU1_R_SDA";
28"I3C_1_SPD_DDRGL_CPU1_R_SCL";
29"RST_CPU1_RSMRST_N";
30"I3C_0_SPD_DDRAF_CPU1_R_SCL";
31"CPU1_PWRGD_OUT";
32"CPU1_SLP_S5_N";
33"CPU1_SLP_S3_N";
34"CPU1_PWRGD_OUT";
35"CPU1_SPD_HOST_CTRL_N";
36"CPU1_SPD_HOST_CTRL_R_N";
37"XTAL_CPU1_X48M_X1";
38"CPU1_SMERR_N";
39"CPU1_FPGA_SPARE0";
40"CPU1_FPGA_SPARE1";
41"CPU1_FPGA_SPARE2";
42"CPU1_FPGA_SPARE3";
43"SLOT2_BUF_SKU_ID0";
44"SLOT2_BUF_SKU_ID1";
45"XTAL_CPU1_X48M_X2";
46"FM_CPU1_SLP_S5_N";
47"FM_CPU1_SLP_S3_N";
48"CPU1_SLP_S5_N";
49"CPU1_SLP_S3_N";
50"INT_CPU1_HP_UBM_N";
51"NC_CPU1_PWR_BTN_N";
52"RST_CPU1_RSMRST_N";
53"CPU1_PWR_GD_IN";
54"RST_CPU1_SYS_N";
55"XTAL_CPU1_X48M_X2";
56"XTAL_CPU1_X48M_X1";
57"CPU1_NMI_SYNC_FLOOD_N";
58"XTAL_CPU1_X32K_X2";
59"XTAL_CPU1_X32K_X1";
60"I3C_0_SPD_DDRAF_CPU1_R_SDA";
61"I3C_1_SPD_DDRGL_CPU1_R_SCL";
62"I3C_1_SPD_DDRGL_CPU1_R_SDA";
63"CLK_100M_CPU1_CLK13_R_DP";
64"CLK_100M_CPU1_CLK13_R_DN";
65"CLK_100M_CPU1_CLK15_R_DP";
66"CLK_100M_CPU1_CLK15_R_DN";
67"SMB_CPU1_SEC_SDA";
68"SMB_CPU1_SEC_SCL";
69"CLK_CPU0_RTCCLK";
70"XTAL_CPU1_X32K_X2";
71"XTAL_CPU1_X32K_X1";
72"CLK_100M_CPU1_CLK13_DP";
73"CLK_100M_CPU1_CLK13_DN";
74"CLK_100M_CPU1_CLK15_DP";
75"CLK_100M_CPU1_CLK15_DN";
76"CLK_100M_CPU1_CLK11_R_DN";
77"CLK_100M_CPU1_CLK11_R_DP";
78"CLK_100M_REF_IN_DP";
79"CLK_100M_REF_IN_DN";
80"PWRGD_CPU1_PWROK";
81"RST_CPU1_RESETL_N";
82"CPU1_FORCE_SELFREFRESH";
83"CPU1_PWRGD_OUT";
84"CPU1_NV_SAVE_N";
85"RST_CPU1_PERST0_N";
86"RST_CPU1_PERST1_N";
87"CLK_CPU1_RTCCLK";
88"IRQ_WAKE_N";
89"CLK_100M_CPU1_CLK11_DP";
90"CLK_100M_CPU1_CLK11_DN";
91"GND\g";
92"GND\g";
%"Q_RES"
"1","(-5525,1050)","0","pure_quanta","I10";
;
LOCATION"R571"
$SEC"1"
CDS_SEC"1"
PACK_TYPE"0402LF"
PART_NUMBER"CS61002JB23"
VALUE"10M"
TOLERANCE"5%"
MATERIAL"CHIP"
WATTAGE"1/16W"
CDS_LIB"pure_quanta";
"B"
$PN"2"45;
"A"
$PN"1"37;
%"UNIVERSAL_GND"
"1","(-5900,1250)","0","pure_quanta_power","I11";
;
HDL_POWER"GND"
CDS_LIB"pure_quanta_power";
"A"1;
%"Q_XTAL_4P_13BI_24GND"
"1","(-5525,1575)","0","pure_quanta","I12";
;
LOCATION"Y4"
$SEC"1"
CDS_SEC"1"
PART_NUMBER"BG648000055"
VALUE"48MHZ"
MATERIAL"MISC "
PART_TYPE"SMLF"
CDS_LMAN_SYM_OUTLINE"-125,175,125,-175"
PIN_NAMES_ROTATE"True"
CDS_LIB"pure_quanta";
"X2"
$PN"3"45;
"G2"
$PN"4"2;
"G1"
$PN"2"1;
"X1"
$PN"1"37;
%"UNIVERSAL_GND"
"1","(-5125,1250)","0","pure_quanta_power","I13";
;
HDL_POWER"GND"
CDS_LIB"pure_quanta_power";
"A"2;
%"Q_RES"
"1","(-8625,2225)","2","pure_quanta","I130";
;
LOCATION"R546"
$SEC"1"
CDS_SEC"1"
VALUE"4.7K"
PACK_TYPE"0402LF"
PART_NUMBER"TMP_QCS24702JB38"
TOLERANCE"5%"
MATERIAL"CHIP"
WATTAGE"1/16W"
CDS_LIB"pure_quanta";
"B"
$PN"2"10;
"A"
$PN"1"18;
%"Q_RES"
"1","(-8625,2275)","2","pure_quanta","I131";
;
LOCATION"R545"
$SEC"1"
CDS_SEC"1"
VALUE"4.7K"
PACK_TYPE"0402LF"
PART_NUMBER"TMP_QCS24702JB38"
TOLERANCE"5%"
MATERIAL"CHIP"
WATTAGE"1/16W"
CDS_LIB"pure_quanta";
"B"
$PN"2"10;
"A"
$PN"1"19;
%"Q_RES"
"1","(-8625,2325)","2","pure_quanta","I132";
;
LOCATION"R544"
$SEC"1"
CDS_SEC"1"
VALUE"4.7K"
PACK_TYPE"0402LF"
PART_NUMBER"TMP_QCS24702JB38"
TOLERANCE"5%"
MATERIAL"CHIP"
WATTAGE"1/16W"
CDS_LIB"pure_quanta";
"B"
$PN"2"10;
"A"
$PN"1"22;
%"UNIVERSAL_POWER"
"1","(-8975,2425)","2","pure_quanta_power","I133";
;
HDL_POWER"PVDD18_S5_P1"
CDS_LIB"pure_quanta_power";
"A"10;
%"Q_RES"
"1","(-8625,2175)","2","pure_quanta","I134";
;
LOCATION"R547"
$SEC"1"
CDS_SEC"1"
VALUE"4.7K"
PACK_TYPE"0402LF"
PART_NUMBER"TMP_QCS24702JB38"
TOLERANCE"5%"
MATERIAL"CHIP"
WATTAGE"1/16W"
CDS_LIB"pure_quanta";
"B"
$PN"2"10;
"A"
$PN"1"15;
%"Q_RES"
"1","(-8625,1625)","2","pure_quanta","I139";
;
LOCATION"R548"
$SEC"1"
CDS_SEC"1"
MATERIAL"EMPTY"
VALUE"4.7K"
PACK_TYPE"0402LF"
PART_NUMBER"TMP_QCS24702JB38"
TOLERANCE"5%"
WATTAGE"1/16W"
CDS_LIB"pure_quanta";
"B"
$PN"2"10;
"A"
$PN"1"32;
%"UNIVERSAL_GND"
"1","(-4900,525)","0","pure_quanta_power","I14";
;
HDL_POWER"GND"
CDS_LIB"pure_quanta_power";
"A"3;
%"Q_RES"
"1","(-8625,1575)","2","pure_quanta","I142";
;
LOCATION"R549"
$SEC"1"
CDS_SEC"1"
MATERIAL"EMPTY"
VALUE"4.7K"
PACK_TYPE"0402LF"
PART_NUMBER"TMP_QCS24702JB38"
TOLERANCE"5%"
WATTAGE"1/16W"
CDS_LIB"pure_quanta";
"B"
$PN"2"10;
"A"
$PN"1"33;
%"Q_RES"
"1","(-8625,2075)","2","pure_quanta","I143";
;
LOCATION"R550"
$SEC"1"
CDS_SEC"1"
VALUE"4.7K"
PACK_TYPE"0402LF"
PART_NUMBER"TMP_QCS24702JB38"
TOLERANCE"5%"
MATERIAL"CHIP"
WATTAGE"1/16W"
CDS_LIB"pure_quanta";
"B"
$PN"2"10;
"A"
$PN"1"17;
%"Q_RES"
"1","(-8625,2025)","2","pure_quanta","I148";
;
LOCATION"R551"
$SEC"1"
CDS_SEC"1"
VALUE"4.7K"
PACK_TYPE"0402LF"
PART_NUMBER"TMP_QCS24702JB38"
TOLERANCE"5%"
MATERIAL"CHIP"
WATTAGE"1/16W"
CDS_LIB"pure_quanta";
"B"
$PN"2"10;
"A"
$PN"1"13;
%"Q_CAP"
"1","(-4900,825)","0","pure_quanta","I15";
;
LOCATION"C237"
$SEC"1"
CDS_SEC"1"
VALUE"3.9P"
TOLERANCE"0.1P"
MATERIAL"NPO"
PART_NUMBER"CH-3916TB01"
PACK_TYPE"C0402"
VOLTAGE"50V"
CDS_LIB"pure_quanta";
"B"
$PN"2"3;
"A"
$PN"1"45;
%"Q_RES"
"1","(-8625,1975)","2","pure_quanta","I155";
;
LOCATION"R553"
$SEC"1"
CDS_SEC"1"
VALUE"4.7K"
PART_NUMBER"TMP_QCS24702JB38"
PACK_TYPE"0402LF"
TOLERANCE"5%"
MATERIAL"CHIP"
WATTAGE"1/16W"
CDS_LIB"pure_quanta";
"B"
$PN"2"10;
"A"
$PN"1"16;
%"Q_RES"
"1","(-8625,1875)","2","pure_quanta","I169";
;
LOCATION"R558"
$SEC"1"
CDS_SEC"1"
VALUE"4.7K"
PACK_TYPE"0402LF"
PART_NUMBER"TMP_QCS24702JB38"
TOLERANCE"5%"
MATERIAL"CHIP"
WATTAGE"1/16W"
CDS_LIB"pure_quanta";
"B"
$PN"2"10;
"A"
$PN"1"11;
%"GENOA_SP5"
"21","(-4375,4475)","0","pure_quanta","I182";
;
LOCATION"U26"
$SEC"21"
CDS_SEC"21"
PART_NUMBER"DGA^6000030"
VALUE"SOCKET6096_13568-001"
MATERIAL"IO"
PART_TYPE"SMLF"
CDS_LIB"pure_quanta"
CDS_LMAN_SYM_OUTLINE"-1100,1800,1100,-1800"
NEEDS_NO_SIZE"TRUE";
"AGPIO7"
$PN"DH4"0;
"NMI_SYNC_FLOOD_L"
$PN"DJ31"57;
"SEC_SCL||AGPIO262"
$PN"B14"68;
"SEC_SDA||AGPIO263"
$PN"D14"67;
"AGPIO257||SGPIO1_CLK||CLK_REQ01_L"
$PN"C14"0;
"PWROK||SVI_RST_L"
$PN"D69"80;
"AGPIO6||DEVSLP1||SATA_ZP1_L"
$PN"DE40"40;
"AGPIO5||DEVSLP0||SATA_ZP0_L"
$PN"DF40"39;
"GENINT_L||PM_INTR_L||UBM_CPRSNT_CHANGE_DET_L||AGPIO89"
$PN"DJ35"50;
"AGPIO22"
$PN"DE32"44;
"AGPIO88"
$PN"DJ29"0;
"AGPIO21"
$PN"DF33"43;
"AGPIO87"
$PN"DG11"0;
"AGPIO109"
$PN"DG32"0;
"AGPIO107"
$PN"DG31"0;
"AGPIO106"
$PN"DF31"0;
"AGPIO105"
$PN"DE30"0;
"AGPIO104"
$PN"DH30"0;
"RESET_L \B"
$PN"B67"81;
"REFCLK100SSC_N||GPP_CLK10N"
$PN"A20"79;
"REFCLK100SSC_P||GPP_CLK10P"
$PN"A19"78;
"SMERR_L||AGPIO24"
$PN"DJ11"38;
"I2C5_SDA||BMC_SDA||SMBUS1_SDA||AGPIO20"
$PN"DJ20"0;
"I2C5_SCL||BMC_SCL||SMBUS1_SCL||AGPIO19"
$PN"DJ21"0;
"I2C4_SDA||HP_SDA||UBM_SDA||AGPIO14"
$PN"DH12"0;
"I2C4_SCL||HP_SCL||UBM_SCL||AGPIO13"
$PN"DG12"0;
"I3C3_SCL||I2C3_SCL||SPD3_SCL||AGPIO151"
$PN"A4"0;
"I3C1_SDA||I2C1_SDA||SPD1_SDA||AGPIO148"
$PN"A5"62;
"AGPIO116||CLK_REQ12_L"
$PN"DH15"42;
"PWRGD_OUT||AGPIO12"
$PN"DH36"83;
"AGPIO259||SGPIO3_CLK"
$PN"B16"0;
"I3C0_SCL||I2C0_SCL||SPD0_SCL||SMBUS0_SCL||AGPIO145"
$PN"A71"30;
"I3C2_SCL||I2C2_SCL||SPD2_SCL||AGPIO149"
$PN"C72"0;
"I3C1_SCL||I2C1_SCL||SPD1_SCL||AGPIO147"
$PN"C7"61;
"I3C0_SDA||I2C0_SDA||SPD0_SDA||SMBUS0_SDA||AGPIO146"
$PN"B71"60;
"AGPIO115||CLK_REQ11_L"
$PN"DH16"41;
"PCIE_RST0_L||AGPIO266"
$PN"D18"85;
"AGPIO256||SGPIO0_CLK"
$PN"A14"0;
"AGPIO258||SGPIO2_CLK||CLK_REQ02_L"
$PN"A13"0;
"I3C3_SDA||I2C3_SDA||SPD3_SDA||AGPIO152"
$PN"B4"0;
"SGPIO_DATAOUT||AGPIO260"
$PN"D15"0;
"I3C2_SDA||I2C2_SDA||SPD2_SDA||AGPIO150"
$PN"B72"0;
"SGPIO_LOAD||AGPIO261"
$PN"B15"0;
"PCIE_RST1_L||AGPIO26"
$PN"DG36"86;
"AGPIO3||SPD_HOST_CTRL_L"
$PN"DE36"36;
"AGPIO4||SATA_ACT_L"
$PN"DF36"0;
"GPP_CLK11P"
$PN"DJ41"77;
"GPP_CLK01P"
$PN"A8"0;
"GPP_CLK12P"
$PN"DJ45"0;
"GPP_CLK02P"
$PN"B6"0;
"GPP_CLK11N"
$PN"DJ42"76;
"GPP_CLK13P"
$PN"DJ53"63;
"GPP_CLK01N"
$PN"A7"0;
"GPP_CLK03P"
$PN"A10"0;
"GPP_CLK12N"
$PN"DJ44"0;
"GPP_CLK14P"
$PN"DJ48"0;
"GPP_CLK02N"
$PN"C6"0;
"GPP_CLK04P"
$PN"B12"0;
"GPP_CLK13N"
$PN"DJ54"64;
"GPP_CLK15P"
$PN"DJ51"65;
"GPP_CLK03N"
$PN"A11"0;
"GPP_CLK05P"
$PN"B9"0;
"GPP_CLK14N"
$PN"DJ47"0;
"GPP_CLK04N"
$PN"C12"0;
"GPP_CLK15N"
$PN"DJ50"66;
"GPP_CLK05N"
$PN"C9"0;
"RTCCLK"
$PN"DH9"87;
"FORCE_SELFREFRESH"
$PN"B63"82;
"NV_SAVE_L"
$PN"B64"84;
"PWR_BTN_L||AGPIO0"
$PN"DH7"51;
"X48M_X2"
$PN"DJ16"55;
"X48M_X1"
$PN"DJ17"56;
"X32K_X2"
$PN"DJ13"58;
"X32K_X1"
$PN"DJ14"59;
"WAKE_L||AGPIO2"
$PN"DJ10"88;
"SYS_RESET_L||AGPIO1"
$PN"DH6"54;
"SLP_S5_L"
$PN"DG4"48;
"SLP_S3_L"
$PN"DJ5"49;
"RSMRST_L \B"
$PN"DG10"52;
"PWR_GOOD"
$PN"DJ8"53;
%"UNIVERSAL_GND"
"1","(-6175,525)","0","pure_quanta_power","I2";
;
HDL_POWER"GND"
CDS_LIB"pure_quanta_power";
"A"4;
%"Q_RES"
"1","(-6900,3475)","0","pure_quanta","I236";
;
LOCATION"R570"
$SEC"1"
CDS_SEC"1"
VALUE"0"
PACK_TYPE"0402LF"
PART_NUMBER"CS00002JB38"
TOLERANCE"5%"
MATERIAL"CHIP"
WATTAGE"1/16W"
CDS_LIB"pure_quanta";
"B"
$PN"2"36;
"A"
$PN"1"35;
%"Q_RES"
"1","(-2250,2175)","0","pure_quanta","I24";
;
LOCATION"R574"
$SEC"1"
CDS_SEC"1"
VALUE"0"
MATERIAL"EMPTY"
PACK_TYPE"0402LF"
PART_NUMBER"CS00002JB38"
TOLERANCE"5%"
WATTAGE"1/16W"
CDS_LIB"pure_quanta";
"B"
$PN"2"71;
"A"
$PN"1"8;
%"VCC_CORE"
"1","(-8525,3225)","0","pure_quanta_power","I246";
;
HDL_POWER"PVDD11_S3_P1"
CDS_LIB"pure_quanta_power";
"A"23;
%"Q_RES"
"2","(-8525,2925)","0","pure_quanta","I247";
;
LOCATION"R563"
$SEC"1"
CDS_SEC"1"
MATERIAL"EMPTY"
TOLERANCE"5%"
VALUE"1K"
PART_NUMBER"TMP_QCS21002JB34"
CDS_LIB"pure_quanta"
WATTAGE"1/16W"
PACK_TYPE"0402LF";
"A"
$PN"1"23;
"B"
$PN"2"26;
%"Q_RES"
"2","(-8700,2925)","0","pure_quanta","I248";
;
LOCATION"R543"
$SEC"1"
CDS_SEC"1"
TOLERANCE"5%"
VALUE"1K"
MATERIAL"EMPTY"
PART_NUMBER"TMP_QCS21002JB34"
PACK_TYPE"0402LF"
WATTAGE"1/16W"
CDS_LIB"pure_quanta";
"A"
$PN"1"23;
"B"
$PN"2"27;
%"Q_RES"
"2","(-8875,2925)","0","pure_quanta","I249";
;
LOCATION"R542"
$SEC"1"
CDS_SEC"1"
MATERIAL"EMPTY"
TOLERANCE"5%"
VALUE"1K"
PART_NUMBER"TMP_QCS21002JB34"
PACK_TYPE"0402LF"
WATTAGE"1/16W"
CDS_LIB"pure_quanta";
"A"
$PN"1"23;
"B"
$PN"2"28;
%"Q_RES"
"2","(-9050,2925)","0","pure_quanta","I250";
;
LOCATION"R541"
$SEC"1"
CDS_SEC"1"
MATERIAL"EMPTY"
TOLERANCE"5%"
VALUE"1K"
PART_NUMBER"TMP_QCS21002JB34"
PACK_TYPE"0402LF"
WATTAGE"1/16W"
CDS_LIB"pure_quanta";
"A"
$PN"1"23;
"B"
$PN"2"25;
%"Q_RES"
"1","(-8525,1100)","1","pure_quanta","I258";
;
LOCATION"R583"
$SEC"1"
CDS_SEC"1"
VALUE"4.7K"
MATERIAL"EMPTY"
PACK_TYPE"0402LF"
PART_NUMBER"TMP_QCS24702JB38"
TOLERANCE"5%"
WATTAGE"1/16W"
CDS_LIB"pure_quanta";
"B"
$PN"2"24;
"A"
$PN"1"29;
%"Q_RES"
"1","(-2250,2425)","0","pure_quanta","I26";
;
LOCATION"R573"
$SEC"1"
CDS_SEC"1"
VALUE"0"
MATERIAL"CHIP"
PACK_TYPE"0402LF"
PART_NUMBER"CS00002JB38"
TOLERANCE"5%"
WATTAGE"1/16W"
CDS_LIB"pure_quanta";
"B"
$PN"2"71;
"A"
$PN"1"69;
%"UNIVERSAL_GND"
"1","(-8525,225)","0","pure_quanta_power","I260";
;
HDL_POWER"GND"
CDS_LIB"pure_quanta_power";
"A"92;
%"Q_RES"
"1","(-8525,375)","1","pure_quanta","I261";
;
LOCATION"R584"
$SEC"1"
CDS_SEC"1"
MATERIAL"EMPTY"
VALUE"4.7K"
PACK_TYPE"0402LF"
PART_NUMBER"TMP_QCS24702JB38"
TOLERANCE"5%"
WATTAGE"1/16W"
CDS_LIB"pure_quanta";
"B"
$PN"2"29;
"A"
$PN"1"92;
%"UNIVERSAL_GND"
"1","(-8750,225)","0","pure_quanta_power","I263";
;
HDL_POWER"GND"
CDS_LIB"pure_quanta_power";
"A"91;
%"UNIVERSAL_POWER"
"1","(-8750,1300)","0","pure_quanta_power","I264";
;
HDL_POWER"PVDD18_S5_P1"
CDS_LIB"pure_quanta_power";
"A"24;
%"Q_RES"
"1","(-8750,1100)","1","pure_quanta","I265";
;
LOCATION"R456"
$SEC"1"
CDS_SEC"1"
VALUE"4.7K"
MATERIAL"EMPTY"
PACK_TYPE"0402LF"
PART_NUMBER"TMP_QCS24702JB38"
TOLERANCE"5%"
WATTAGE"1/16W"
CDS_LIB"pure_quanta";
"B"
$PN"2"24;
"A"
$PN"1"31;
%"Q_RES"
"1","(-8750,375)","1","pure_quanta","I266";
;
LOCATION"R491"
$SEC"1"
CDS_SEC"1"
VALUE"4.7K"
MATERIAL"EMPTY"
PACK_TYPE"0402LF"
PART_NUMBER"TMP_QCS24702JB38"
TOLERANCE"5%"
WATTAGE"1/16W"
CDS_LIB"pure_quanta";
"B"
$PN"2"31;
"A"
$PN"1"91;
%"Q_RES"
"1","(-2125,4175)","0","pure_quanta","I283";
;
LOCATION"R1345"
$SEC"1"
CDS_SEC"1"
VALUE"0"
PACK_TYPE"0402LF"
PART_NUMBER"CS00002JB38"
TOLERANCE"5%"
MATERIAL"CHIP"
WATTAGE"1/16W"
CDS_LIB"pure_quanta";
"B"
$PN"2"89;
"A"
$PN"1"77;
%"Q_RES"
"1","(-2125,4125)","0","pure_quanta","I284";
;
LOCATION"R1346"
$SEC"1"
CDS_SEC"1"
VALUE"0"
PACK_TYPE"0402LF"
PART_NUMBER"CS00002JB38"
TOLERANCE"5%"
MATERIAL"CHIP"
WATTAGE"1/16W"
CDS_LIB"pure_quanta";
"B"
$PN"2"90;
"A"
$PN"1"76;
%"Q_RES"
"1","(-2125,3875)","0","pure_quanta","I285";
;
LOCATION"R1347"
$SEC"1"
CDS_SEC"1"
VALUE"0"
PACK_TYPE"0402LF"
PART_NUMBER"CS00002JB38"
TOLERANCE"5%"
MATERIAL"CHIP"
WATTAGE"1/16W"
CDS_LIB"pure_quanta";
"B"
$PN"2"72;
"A"
$PN"1"63;
%"Q_RES"
"1","(-2125,3825)","0","pure_quanta","I286";
;
LOCATION"R1348"
$SEC"1"
CDS_SEC"1"
VALUE"0"
PACK_TYPE"0402LF"
PART_NUMBER"CS00002JB38"
TOLERANCE"5%"
MATERIAL"CHIP"
WATTAGE"1/16W"
CDS_LIB"pure_quanta";
"B"
$PN"2"73;
"A"
$PN"1"64;
%"Q_RES"
"1","(-2125,3525)","0","pure_quanta","I287";
;
LOCATION"R1350"
$SEC"1"
CDS_SEC"1"
VALUE"0"
PACK_TYPE"0402LF"
PART_NUMBER"CS00002JB38"
TOLERANCE"5%"
MATERIAL"CHIP"
WATTAGE"1/16W"
CDS_LIB"pure_quanta";
"B"
$PN"2"75;
"A"
$PN"1"66;
%"Q_RES"
"1","(-2125,3575)","0","pure_quanta","I288";
;
LOCATION"R1349"
$SEC"1"
CDS_SEC"1"
VALUE"0"
PACK_TYPE"0402LF"
PART_NUMBER"CS00002JB38"
TOLERANCE"5%"
MATERIAL"CHIP"
WATTAGE"1/16W"
CDS_LIB"pure_quanta";
"B"
$PN"2"74;
"A"
$PN"1"65;
%"Q_RES"
"1","(-8625,1925)","0","pure_quanta","I289";
;
LOCATION"R556"
$SEC"1"
CDS_SEC"1"
MATERIAL"EMPTY"
VALUE"1K"
PACK_TYPE"0402LF"
PART_NUMBER"TMP_QCS21002JB34"
TOLERANCE"5%"
WATTAGE"1/16W"
CDS_LIB"pure_quanta";
"B"
$PN"2"12;
"A"
$PN"1"10;
%"Q_RES"
"1","(-8625,1825)","0","pure_quanta","I290";
;
LOCATION"R559"
$SEC"1"
CDS_SEC"1"
VALUE"2.2K"
PACK_TYPE"0402LF"
PART_NUMBER"CS22202JB07"
TOLERANCE"5%"
MATERIAL"CHIP"
WATTAGE"1/16W"
CDS_LIB"pure_quanta";
"B"
$PN"2"20;
"A"
$PN"1"10;
%"UNIVERSAL_POWER"
"1","(-7375,4975)","2","pure_quanta_power","I291";
;
HDL_POWER"PVDD18_S5_P1"
CDS_LIB"pure_quanta_power";
"A"5;
%"Q_RES"
"1","(-7050,4875)","0","pure_quanta","I292";
;
LOCATION"R1424"
$SEC"1"
CDS_SEC"1"
VALUE"2.2K"
PACK_TYPE"0402LF"
PART_NUMBER"CS22202JB07"
TOLERANCE"5%"
MATERIAL"CHIP"
WATTAGE"1/16W"
CDS_LIB"pure_quanta";
"B"
$PN"2"50;
"A"
$PN"1"5;
%"Q_RES"
"1","(-8625,1675)","2","pure_quanta","I293";
;
LOCATION"R561"
$SEC"1"
CDS_SEC"1"
MATERIAL"EMPTY"
VALUE"4.7K"
PACK_TYPE"0402LF"
PART_NUMBER"TMP_QCS24702JB38"
TOLERANCE"5%"
WATTAGE"1/16W"
CDS_LIB"pure_quanta";
"B"
$PN"2"10;
"A"
$PN"1"34;
%"Q_RES"
"1","(-8625,2125)","0","pure_quanta","I294";
;
LOCATION"R557"
$SEC"1"
CDS_SEC"1"
VALUE"1K"
MATERIAL"EMPTY"
CDS_LIB"pure_quanta"
WATTAGE"1/16W"
TOLERANCE"5%"
PART_NUMBER"TMP_QCS21002JB34"
PACK_TYPE"0402LF";
"B"
$PN"2"14;
"A"
$PN"1"10;
%"Q_RES"
"1","(-8625,1775)","0","pure_quanta","I295";
;
LOCATION"R562"
$SEC"1"
CDS_SEC"1"
VALUE"2.2K"
PACK_TYPE"0402LF"
PART_NUMBER"CS22202JB07"
TOLERANCE"5%"
MATERIAL"CHIP"
WATTAGE"1/16W"
CDS_LIB"pure_quanta";
"B"
$PN"2"21;
"A"
$PN"1"10;
%"Q_RES"
"1","(-2250,2125)","0","pure_quanta","I296";
;
LOCATION"R575"
$SEC"1"
CDS_SEC"1"
VALUE"0"
MATERIAL"EMPTY"
PACK_TYPE"0402LF"
PART_NUMBER"CS00002JB38"
TOLERANCE"5%"
WATTAGE"1/16W"
CDS_LIB"pure_quanta";
"B"
$PN"2"70;
"A"
$PN"1"9;
%"Q_RES"
"1","(-6625,5775)","0","pure_quanta","I297";
;
LOCATION"R191"
$SEC"1"
CDS_SEC"1"
VALUE"0"
MATERIAL"EMPTY"
ROOM"RST_CPU0_PLD_TO_DIMM"
PACK_TYPE"0402LF"
PART_NUMBER"CS00002JB38"
TOLERANCE"5%"
WATTAGE"1/16W"
CDS_LIB"pure_quanta"
BOM_COST"MEM";
"B"
$PN"2"48;
"A"
$PN"1"46;
%"Q_RES"
"1","(-6625,5725)","0","pure_quanta","I298";
;
LOCATION"R192"
$SEC"1"
CDS_SEC"1"
VALUE"0"
MATERIAL"EMPTY"
ROOM"RST_CPU0_PLD_TO_DIMM"
PACK_TYPE"0402LF"
PART_NUMBER"CS00002JB38"
TOLERANCE"5%"
WATTAGE"1/16W"
CDS_LIB"pure_quanta"
BOM_COST"MEM";
"B"
$PN"2"49;
"A"
$PN"1"47;
%"Q_CAP"
"1","(-6175,825)","0","pure_quanta","I3";
;
LOCATION"C236"
$SEC"1"
CDS_SEC"1"
PACK_TYPE"C0402"
VOLTAGE"50V"
PART_NUMBER"CH-3916TB01"
VALUE"3.9P"
TOLERANCE"0.1P"
MATERIAL"NPO"
CDS_LIB"pure_quanta";
"B"
$PN"2"4;
"A"
$PN"1"37;
%"UNIVERSAL_GND"
"1","(-4125,650)","0","pure_quanta_power","I4";
;
HDL_POWER"GND"
CDS_LIB"pure_quanta_power";
"A"6;
%"Q_CAP"
"1","(-4125,1050)","0","pure_quanta","I5";
;
LOCATION"C238"
$SEC"1"
CDS_SEC"1"
VALUE"10PF"
VOLTAGE"50V"
PACK_TYPE"0402"
MATERIAL"NPO"
TOLERANCE"1%"
PART_NUMBER"TMP_QCH0106F0B00"
CDS_LIB"pure_quanta";
"B"
$PN"2"6;
"A"
$PN"1"8;
%"Q_RES"
"1","(-3625,1450)","0","pure_quanta","I6";
;
LOCATION"R572"
$SEC"1"
CDS_SEC"1"
PART_NUMBER"CS62002JB18"
VALUE"20M"
MATERIAL"CHIP"
TOLERANCE"5%"
WATTAGE"1/16W"
PACK_TYPE"0402LF"
CDS_LIB"pure_quanta";
"B"
$PN"2"9;
"A"
$PN"1"8;
%"Q_CRYSTAL"
"1","(-3625,1750)","0","pure_quanta","I7";
;
LOCATION"Y5"
$SEC"1"
CDS_SEC"1"
PACK_TYPE"SMLF"
PART_NUMBER"BG632768012"
VALUE"32.768KHZ"
MATERIAL"EMPTY"
NEEDS_NO_SIZE"TRUE"
CDS_LIB"pure_quanta";
"2"
$PN"2"9;
"1"
$PN"1"8;
%"UNIVERSAL_GND"
"1","(-3075,675)","0","pure_quanta_power","I8";
;
HDL_POWER"GND"
CDS_LIB"pure_quanta_power";
"A"7;
%"Q_CAP"
"1","(-3075,1075)","0","pure_quanta","I9";
;
LOCATION"C239"
$SEC"1"
CDS_SEC"1"
VALUE"10PF"
VOLTAGE"50V"
PACK_TYPE"0402"
MATERIAL"NPO"
TOLERANCE"1%"
PART_NUMBER"TMP_QCH0106F0B00"
CDS_LIB"pure_quanta";
"B"
$PN"2"7;
"A"
$PN"1"9;
END.
